(kicad_pcb
	(version 20260206)
	(generator "pcbnew")
	(generator_version "10.0")
	(general
		(thickness 1.6)
		(legacy_teardrops no)
	)
	(paper "A4")
	(title_block
		(title "Wiwynn_Tioga_Pass_MB.brd")
		(comment 1 "Tioga Pass / footprints 1034-1041 of 4770")
	)
	(layers
		(0 "F.Cu" signal "TOP")
		(4 "In1.Cu" signal "L2GND")
		(6 "In2.Cu" signal "L3")
		(8 "In3.Cu" signal "L4GND")
		(10 "In4.Cu" signal "L5")
		(12 "In5.Cu" signal "L6GND")
		(14 "In6.Cu" signal "L7VCC")
		(16 "In7.Cu" signal "L8VCC")
		(18 "In8.Cu" signal "L9GND")
		(20 "In9.Cu" signal "L10")
		(22 "In10.Cu" signal "L11GND")
		(24 "In11.Cu" signal "L12")
		(26 "In12.Cu" signal "L13GND")
		(2 "B.Cu" signal "BOTTOM")
		(9 "F.Adhes" user "F.Adhesive")
		(11 "B.Adhes" user "B.Adhesive")
		(13 "F.Paste" user "Package Geometry/Pastemask Top")
		(15 "B.Paste" user "Package Geometry/Pastemask Bottom")
		(5 "F.SilkS" user "Ref Des/Silkscreen Top")
		(7 "B.SilkS" user "Ref Des/Silkscreen Bottom")
		(1 "F.Mask" user "Board Geometry/Soldermask Top")
		(3 "B.Mask" user "Board Geometry/Soldermask Bottom")
		(17 "Dwgs.User" user "User.Drawings")
		(19 "Cmts.User" user "User.Comments")
		(21 "Eco1.User" user "User.Eco1")
		(23 "Eco2.User" user "User.Eco2")
		(25 "Edge.Cuts" user "Board Geometry/Outline")
		(27 "Margin" user)
		(31 "F.CrtYd" user "Package Geometry/Place Bound Top")
		(29 "B.CrtYd" user "Package Geometry/Place Bound Bottom")
		(35 "F.Fab" user "Ref Des/Assembly Top")
		(33 "B.Fab" user "Ref Des/Assembly Bottom")
	)
	(footprint ""
		(layer "F.Cu")
		(at 10.414 -68.0593 180)
		(property "Reference" "R1D47"
			(at 0 0 180)
			(layer "F.SilkS")
			(hide yes)
			(effects
				(font
					(size 1.27 1.27)
				)
			)
		)
		(property "Value" ""
			(at 0 0 180)
			(layer "F.Fab")
			(effects
				(font
					(size 1.27 1.27)
				)
			)
		)
		(duplicate_pad_numbers_are_jumpers no)
		(fp_rect
			(start -0.2794 -0.1016)
			(end 0.2794 0.9906)
			(stroke
				(width 0)
				(type default)
			)
			(fill no)
			(layer "F.CrtYd")
		)
		(fp_line
			(start 0.2794 0.9906)
			(end 0.2794 -0.1016)
			(stroke
				(width 0.1)
				(type default)
			)
			(layer "F.Fab")
		)
		(fp_line
			(start 0.2794 -0.1016)
			(end -0.2794 -0.1016)
			(stroke
				(width 0.1)
				(type default)
			)
			(layer "F.Fab")
		)
		(fp_line
			(start -0.2794 0.9906)
			(end 0.2794 0.9906)
			(stroke
				(width 0.1)
				(type default)
			)
			(layer "F.Fab")
		)
		(fp_line
			(start -0.2794 -0.1016)
			(end -0.2794 0.9906)
			(stroke
				(width 0.1)
				(type default)
			)
			(layer "F.Fab")
		)
		(pad "1" smd rect
			(at 0 0 180)
			(size 0.508 0.508)
			(layers "F.Cu" "F.Mask" "F.Paste")
			(net "P12V_HSC_SENN0")
		)
		(pad "2" smd rect
			(at 0 0.889 180)
			(size 0.508 0.508)
			(layers "F.Cu" "F.Mask" "F.Paste")
			(net "A_HSC_HSN")
		)
		(zone
			(layer "F.Cu")
			(hatch none 0.5)
			(connect_pads
				(clearance 0)
			)
			(min_thickness 0.25)
			(keepout
				(tracks not_allowed)
				(vias allowed)
				(pads allowed)
				(copperpour not_allowed)
				(footprints allowed)
			)
			(placement
				(enabled no)
				(sheetname "")
			)
			(fill
				(thermal_gap 0.5)
				(thermal_bridge_width 0.5)
				(island_removal_mode 0)
			)
			(polygon
				(pts
					(xy 10.668 -68.3133) (xy 10.668 -68.6943) (xy 10.16 -68.6943) (xy 10.16 -68.3133)
				)
			)
		)
		(zone
			(layer "F.Cu")
			(hatch none 0.5)
			(connect_pads
				(clearance 0)
			)
			(min_thickness 0.25)
			(keepout
				(tracks allowed)
				(vias not_allowed)
				(pads allowed)
				(copperpour not_allowed)
				(footprints allowed)
			)
			(placement
				(enabled no)
				(sheetname "")
			)
			(fill
				(thermal_gap 0.5)
				(thermal_bridge_width 0.5)
				(island_removal_mode 0)
			)
			(polygon
				(pts
					(xy 10.668 -68.3133) (xy 10.668 -68.6943) (xy 10.16 -68.6943) (xy 10.16 -68.3133)
				)
			)
		)
	)
	(footprint ""
		(layer "F.Cu")
		(at 162.0012 -74.9808 90)
		(property "Reference" "R3D14"
			(at 0 0 90)
			(layer "F.SilkS")
			(hide yes)
			(effects
				(font
					(size 1.27 1.27)
				)
			)
		)
		(property "Value" ""
			(at 0 0 90)
			(layer "F.Fab")
			(effects
				(font
					(size 1.27 1.27)
				)
			)
		)
		(duplicate_pad_numbers_are_jumpers no)
		(fp_poly
			(pts
				(xy -0.4953 -0.2032) (xy 0.4953 -0.2032) (xy 0.4953 1.6002) (xy -0.4953 1.6002)
			)
			(stroke
				(width 0)
				(type default)
			)
			(fill no)
			(layer "F.CrtYd")
		)
		(fp_line
			(start 0.4953 -0.2032)
			(end 0.4953 1.6002)
			(stroke
				(width 0.1)
				(type default)
			)
			(layer "F.Fab")
		)
		(fp_line
			(start -0.4953 -0.2032)
			(end 0.4953 -0.2032)
			(stroke
				(width 0.1)
				(type default)
			)
			(layer "F.Fab")
		)
		(fp_line
			(start 0.4953 1.6002)
			(end -0.4953 1.6002)
			(stroke
				(width 0.1)
				(type default)
			)
			(layer "F.Fab")
		)
		(fp_line
			(start -0.4953 1.6002)
			(end -0.4953 -0.2032)
			(stroke
				(width 0.1)
				(type default)
			)
			(layer "F.Fab")
		)
		(pad "1" smd rect
			(at 0 0 90)
			(size 0.762 0.889)
			(layers "F.Cu" "F.Mask" "F.Paste")
			(net "P3V3_DB1200")
		)
		(pad "2" smd rect
			(at 0 1.397 90)
			(size 0.762 0.889)
			(layers "F.Cu" "F.Mask" "F.Paste")
			(net "P3V3_DB1200_A")
		)
		(zone
			(layer "F.Cu")
			(hatch none 0.5)
			(connect_pads
				(clearance 0)
			)
			(min_thickness 0.25)
			(keepout
				(tracks allowed)
				(vias not_allowed)
				(pads allowed)
				(copperpour not_allowed)
				(footprints allowed)
			)
			(placement
				(enabled no)
				(sheetname "")
			)
			(fill
				(thermal_gap 0.5)
				(thermal_bridge_width 0.5)
				(island_removal_mode 0)
			)
			(polygon
				(pts
					(xy 162.9537 -75.3618) (xy 162.4457 -75.3618) (xy 162.4457 -74.5998) (xy 162.9537 -74.5998)
				)
			)
		)
		(zone
			(layer "F.Cu")
			(hatch none 0.5)
			(connect_pads
				(clearance 0)
			)
			(min_thickness 0.25)
			(keepout
				(tracks not_allowed)
				(vias allowed)
				(pads allowed)
				(copperpour not_allowed)
				(footprints allowed)
			)
			(placement
				(enabled no)
				(sheetname "")
			)
			(fill
				(thermal_gap 0.5)
				(thermal_bridge_width 0.5)
				(island_removal_mode 0)
			)
			(polygon
				(pts
					(xy 162.9537 -74.5998) (xy 162.9537 -75.3618) (xy 162.4457 -75.3618) (xy 162.4457 -74.5998)
				)
			)
		)
	)
	(footprint ""
		(layer "F.Cu")
		(at 392.165078 -86.569042)
		(property "Reference" "R3P64"
			(at 0 0 0)
			(layer "F.SilkS")
			(hide yes)
			(effects
				(font
					(size 1.27 1.27)
				)
			)
		)
		(property "Value" ""
			(at 0 0 0)
			(layer "F.Fab")
			(effects
				(font
					(size 1.27 1.27)
				)
			)
		)
		(duplicate_pad_numbers_are_jumpers no)
		(fp_poly
			(pts
				(xy -0.2794 -0.1016) (xy 0.2794 -0.1016) (xy 0.2794 0.9906) (xy -0.2794 0.9906)
			)
			(stroke
				(width 0)
				(type default)
			)
			(fill no)
			(layer "F.CrtYd")
		)
		(fp_line
			(start -0.2794 -0.1016)
			(end -0.2794 0.9906)
			(stroke
				(width 0.1)
				(type default)
			)
			(layer "F.Fab")
		)
		(fp_line
			(start -0.2794 0.9906)
			(end 0.2794 0.9906)
			(stroke
				(width 0.1)
				(type default)
			)
			(layer "F.Fab")
		)
		(fp_line
			(start 0.2794 -0.1016)
			(end -0.2794 -0.1016)
			(stroke
				(width 0.1)
				(type default)
			)
			(layer "F.Fab")
		)
		(fp_line
			(start 0.2794 0.9906)
			(end 0.2794 -0.1016)
			(stroke
				(width 0.1)
				(type default)
			)
			(layer "F.Fab")
		)
		(pad "1" smd rect
			(at 0 0)
			(size 0.508 0.508)
			(layers "F.Cu" "F.Mask" "F.Paste")
			(net "FM_FLASH_ATTACH_CFG_STRAP")
		)
		(pad "2" smd rect
			(at 0 0.889)
			(size 0.508 0.508)
			(layers "F.Cu" "F.Mask" "F.Paste")
			(net "GND")
		)
		(zone
			(layer "F.Cu")
			(hatch none 0.5)
			(connect_pads
				(clearance 0)
			)
			(min_thickness 0.25)
			(keepout
				(tracks allowed)
				(vias not_allowed)
				(pads allowed)
				(copperpour not_allowed)
				(footprints allowed)
			)
			(placement
				(enabled no)
				(sheetname "")
			)
			(fill
				(thermal_gap 0.5)
				(thermal_bridge_width 0.5)
				(island_removal_mode 0)
			)
			(polygon
				(pts
					(xy 391.911078 -86.315042) (xy 392.419078 -86.315042) (xy 392.419078 -85.934042) (xy 391.911078 -85.934042)
				)
			)
		)
		(zone
			(layer "F.Cu")
			(hatch none 0.5)
			(connect_pads
				(clearance 0)
			)
			(min_thickness 0.25)
			(keepout
				(tracks not_allowed)
				(vias allowed)
				(pads allowed)
				(copperpour not_allowed)
				(footprints allowed)
			)
			(placement
				(enabled no)
				(sheetname "")
			)
			(fill
				(thermal_gap 0.5)
				(thermal_bridge_width 0.5)
				(island_removal_mode 0)
			)
			(polygon
				(pts
					(xy 391.911078 -85.934042) (xy 392.419078 -85.934042) (xy 392.419078 -86.315042) (xy 391.911078 -86.315042)
				)
			)
		)
	)
	(footprint ""
		(layer "F.Cu")
		(at 400.489674 -33.50514)
		(property "Reference" "R8C16"
			(at 0 0 0)
			(layer "F.SilkS")
			(hide yes)
			(effects
				(font
					(size 1.27 1.27)
				)
			)
		)
		(property "Value" ""
			(at 0 0 0)
			(layer "F.Fab")
			(effects
				(font
					(size 1.27 1.27)
				)
			)
		)
		(duplicate_pad_numbers_are_jumpers no)
		(fp_poly
			(pts
				(xy -0.2794 -0.1016) (xy 0.2794 -0.1016) (xy 0.2794 0.9906) (xy -0.2794 0.9906)
			)
			(stroke
				(width 0)
				(type default)
			)
			(fill no)
			(layer "F.CrtYd")
		)
		(fp_line
			(start -0.2794 -0.1016)
			(end -0.2794 0.9906)
			(stroke
				(width 0.1)
				(type default)
			)
			(layer "F.Fab")
		)
		(fp_line
			(start -0.2794 0.9906)
			(end 0.2794 0.9906)
			(stroke
				(width 0.1)
				(type default)
			)
			(layer "F.Fab")
		)
		(fp_line
			(start 0.2794 -0.1016)
			(end -0.2794 -0.1016)
			(stroke
				(width 0.1)
				(type default)
			)
			(layer "F.Fab")
		)
		(fp_line
			(start 0.2794 0.9906)
			(end 0.2794 -0.1016)
			(stroke
				(width 0.1)
				(type default)
			)
			(layer "F.Fab")
		)
		(pad "1" smd rect
			(at 0 0)
			(size 0.508 0.508)
			(layers "F.Cu" "F.Mask" "F.Paste")
			(net "P3V3_STBY")
		)
		(pad "2" smd rect
			(at 0 0.889)
			(size 0.508 0.508)
			(layers "F.Cu" "F.Mask" "F.Paste")
			(net "SMB_HOST_STBY_LVC3_SDA_R")
		)
		(zone
			(layer "F.Cu")
			(hatch none 0.5)
			(connect_pads
				(clearance 0)
			)
			(min_thickness 0.25)
			(keepout
				(tracks allowed)
				(vias not_allowed)
				(pads allowed)
				(copperpour not_allowed)
				(footprints allowed)
			)
			(placement
				(enabled no)
				(sheetname "")
			)
			(fill
				(thermal_gap 0.5)
				(thermal_bridge_width 0.5)
				(island_removal_mode 0)
			)
			(polygon
				(pts
					(xy 400.235674 -33.25114) (xy 400.743674 -33.25114) (xy 400.743674 -32.87014) (xy 400.235674 -32.87014)
				)
			)
		)
		(zone
			(layer "F.Cu")
			(hatch none 0.5)
			(connect_pads
				(clearance 0)
			)
			(min_thickness 0.25)
			(keepout
				(tracks not_allowed)
				(vias allowed)
				(pads allowed)
				(copperpour not_allowed)
				(footprints allowed)
			)
			(placement
				(enabled no)
				(sheetname "")
			)
			(fill
				(thermal_gap 0.5)
				(thermal_bridge_width 0.5)
				(island_removal_mode 0)
			)
			(polygon
				(pts
					(xy 400.235674 -32.87014) (xy 400.743674 -32.87014) (xy 400.743674 -33.25114) (xy 400.235674 -33.25114)
				)
			)
		)
	)
	(footprint ""
		(layer "F.Cu")
		(at 103.16464 -77.636116)
		(property "Reference" "C2D27"
			(at 0 0 0)
			(layer "F.SilkS")
			(hide yes)
			(effects
				(font
					(size 1.27 1.27)
				)
			)
		)
		(property "Value" ""
			(at 0 0 0)
			(layer "F.Fab")
			(effects
				(font
					(size 1.27 1.27)
				)
			)
		)
		(duplicate_pad_numbers_are_jumpers no)
		(fp_poly
			(pts
				(xy -0.4953 -0.2032) (xy 0.4953 -0.2032) (xy 0.4953 1.6002) (xy -0.4953 1.6002)
			)
			(stroke
				(width 0)
				(type default)
			)
			(fill no)
			(layer "F.CrtYd")
		)
		(fp_line
			(start -0.4953 -0.2032)
			(end 0.4953 -0.2032)
			(stroke
				(width 0.1)
				(type default)
			)
			(layer "F.Fab")
		)
		(fp_line
			(start -0.4953 1.6002)
			(end -0.4953 -0.2032)
			(stroke
				(width 0.1)
				(type default)
			)
			(layer "F.Fab")
		)
		(fp_line
			(start 0.4953 -0.2032)
			(end 0.4953 1.6002)
			(stroke
				(width 0.1)
				(type default)
			)
			(layer "F.Fab")
		)
		(fp_line
			(start 0.4953 1.6002)
			(end -0.4953 1.6002)
			(stroke
				(width 0.1)
				(type default)
			)
			(layer "F.Fab")
		)
		(pad "1" smd rect
			(at 0 0)
			(size 0.762 0.889)
			(layers "F.Cu" "F.Mask" "F.Paste")
			(net "PVCCIN_CPU1")
		)
		(pad "2" smd rect
			(at 0 1.397)
			(size 0.762 0.889)
			(layers "F.Cu" "F.Mask" "F.Paste")
			(net "GND")
		)
		(zone
			(layer "F.Cu")
			(hatch none 0.5)
			(connect_pads
				(clearance 0)
			)
			(min_thickness 0.25)
			(keepout
				(tracks not_allowed)
				(vias allowed)
				(pads allowed)
				(copperpour not_allowed)
				(footprints allowed)
			)
			(placement
				(enabled no)
				(sheetname "")
			)
			(fill
				(thermal_gap 0.5)
				(thermal_bridge_width 0.5)
				(island_removal_mode 0)
			)
			(polygon
				(pts
					(xy 102.78364 -77.191616) (xy 103.54564 -77.191616) (xy 103.54564 -76.683616) (xy 102.78364 -76.683616)
				)
			)
		)
	)
	(footprint ""
		(layer "F.Cu")
		(at 100.903024 -68.412614 180)
		(property "Reference" "C2D43"
			(at 0 0 180)
			(layer "F.SilkS")
			(hide yes)
			(effects
				(font
					(size 1.27 1.27)
				)
			)
		)
		(property "Value" ""
			(at 0 0 180)
			(layer "F.Fab")
			(effects
				(font
					(size 1.27 1.27)
				)
			)
		)
		(duplicate_pad_numbers_are_jumpers no)
		(fp_poly
			(pts
				(xy -0.4953 -0.2032) (xy 0.4953 -0.2032) (xy 0.4953 1.6002) (xy -0.4953 1.6002)
			)
			(stroke
				(width 0)
				(type default)
			)
			(fill no)
			(layer "F.CrtYd")
		)
		(fp_line
			(start 0.4953 1.6002)
			(end -0.4953 1.6002)
			(stroke
				(width 0.1)
				(type default)
			)
			(layer "F.Fab")
		)
		(fp_line
			(start 0.4953 -0.2032)
			(end 0.4953 1.6002)
			(stroke
				(width 0.1)
				(type default)
			)
			(layer "F.Fab")
		)
		(fp_line
			(start -0.4953 1.6002)
			(end -0.4953 -0.2032)
			(stroke
				(width 0.1)
				(type default)
			)
			(layer "F.Fab")
		)
		(fp_line
			(start -0.4953 -0.2032)
			(end 0.4953 -0.2032)
			(stroke
				(width 0.1)
				(type default)
			)
			(layer "F.Fab")
		)
		(pad "1" smd rect
			(at 0 0 180)
			(size 0.762 0.889)
			(layers "F.Cu" "F.Mask" "F.Paste")
			(net "PVDDQ_GHJ")
		)
		(pad "2" smd rect
			(at 0 1.397 180)
			(size 0.762 0.889)
			(layers "F.Cu" "F.Mask" "F.Paste")
			(net "GND")
		)
		(zone
			(layer "F.Cu")
			(hatch none 0.5)
			(connect_pads
				(clearance 0)
			)
			(min_thickness 0.25)
			(keepout
				(tracks not_allowed)
				(vias allowed)
				(pads allowed)
				(copperpour not_allowed)
				(footprints allowed)
			)
			(placement
				(enabled no)
				(sheetname "")
			)
			(fill
				(thermal_gap 0.5)
				(thermal_bridge_width 0.5)
				(island_removal_mode 0)
			)
			(polygon
				(pts
					(xy 101.284024 -68.857114) (xy 100.522024 -68.857114) (xy 100.522024 -69.365114) (xy 101.284024 -69.365114)
				)
			)
		)
	)
	(footprint ""
		(layer "F.Cu")
		(at 276.978872 -73.318116)
		(property "Reference" "C6D8"
			(at 0 0 0)
			(layer "F.SilkS")
			(hide yes)
			(effects
				(font
					(size 1.27 1.27)
				)
			)
		)
		(property "Value" ""
			(at 0 0 0)
			(layer "F.Fab")
			(effects
				(font
					(size 1.27 1.27)
				)
			)
		)
		(duplicate_pad_numbers_are_jumpers no)
		(fp_poly
			(pts
				(xy -0.4953 -0.2032) (xy 0.4953 -0.2032) (xy 0.4953 1.6002) (xy -0.4953 1.6002)
			)
			(stroke
				(width 0)
				(type default)
			)
			(fill no)
			(layer "F.CrtYd")
		)
		(fp_line
			(start -0.4953 -0.2032)
			(end 0.4953 -0.2032)
			(stroke
				(width 0.1)
				(type default)
			)
			(layer "F.Fab")
		)
		(fp_line
			(start -0.4953 1.6002)
			(end -0.4953 -0.2032)
			(stroke
				(width 0.1)
				(type default)
			)
			(layer "F.Fab")
		)
		(fp_line
			(start 0.4953 -0.2032)
			(end 0.4953 1.6002)
			(stroke
				(width 0.1)
				(type default)
			)
			(layer "F.Fab")
		)
		(fp_line
			(start 0.4953 1.6002)
			(end -0.4953 1.6002)
			(stroke
				(width 0.1)
				(type default)
			)
			(layer "F.Fab")
		)
		(pad "1" smd rect
			(at 0 0)
			(size 0.762 0.889)
			(layers "F.Cu" "F.Mask" "F.Paste")
			(net "PVCCMCP_CPU0")
		)
		(pad "2" smd rect
			(at 0 1.397)
			(size 0.762 0.889)
			(layers "F.Cu" "F.Mask" "F.Paste")
			(net "GND")
		)
		(zone
			(layer "F.Cu")
			(hatch none 0.5)
			(connect_pads
				(clearance 0)
			)
			(min_thickness 0.25)
			(keepout
				(tracks not_allowed)
				(vias allowed)
				(pads allowed)
				(copperpour not_allowed)
				(footprints allowed)
			)
			(placement
				(enabled no)
				(sheetname "")
			)
			(fill
				(thermal_gap 0.5)
				(thermal_bridge_width 0.5)
				(island_removal_mode 0)
			)
			(polygon
				(pts
					(xy 276.597872 -72.873616) (xy 277.359872 -72.873616) (xy 277.359872 -72.365616) (xy 276.597872 -72.365616)
				)
			)
		)
	)
	(footprint ""
		(layer "F.Cu")
		(at 478.545144 -14.478508 -90)
		(property "Reference" "R9G19"
			(at -0.8382 -0.67818 270)
			(unlocked yes)
			(layer "F.SilkS")
			(effects
				(font
					(size 0.4064 0.254)
					(thickness 0.1524)
				)
				(justify left)
			)
		)
		(property "Value" ""
			(at 0 0 270)
			(layer "F.Fab")
			(effects
				(font
					(size 1.27 1.27)
				)
			)
		)
		(duplicate_pad_numbers_are_jumpers no)
		(fp_poly
			(pts
				(xy -0.2794 -0.1016) (xy 0.2794 -0.1016) (xy 0.2794 0.9906) (xy -0.2794 0.9906)
			)
			(stroke
				(width 0)
				(type default)
			)
			(fill no)
			(layer "F.CrtYd")
		)
		(fp_line
			(start -0.2794 0.9906)
			(end 0.2794 0.9906)
			(stroke
				(width 0.1)
				(type default)
			)
			(layer "F.Fab")
		)
		(fp_line
			(start 0.2794 0.9906)
			(end 0.2794 -0.1016)
			(stroke
				(width 0.1)
				(type default)
			)
			(layer "F.Fab")
		)
		(fp_line
			(start -0.2794 -0.1016)
			(end -0.2794 0.9906)
			(stroke
				(width 0.1)
				(type default)
			)
			(layer "F.Fab")
		)
		(fp_line
			(start 0.2794 -0.1016)
			(end -0.2794 -0.1016)
			(stroke
				(width 0.1)
				(type default)
			)
			(layer "F.Fab")
		)
		(pad "1" smd rect
			(at 0 0 270)
			(size 0.508 0.508)
			(layers "F.Cu" "F.Mask" "F.Paste")
			(net "NIC_MDI_SPRV_RJ45_1_DP")
		)
		(pad "2" smd rect
			(at 0 0.889 270)
			(size 0.508 0.508)
			(layers "F.Cu" "F.Mask" "F.Paste")
			(net "NIC_MDI_SPRV_RJ45_1_R_DP")
		)
		(zone
			(layer "F.Cu")
			(hatch none 0.5)
			(connect_pads
				(clearance 0)
			)
			(min_thickness 0.25)
			(keepout
				(tracks not_allowed)
				(vias allowed)
				(pads allowed)
				(copperpour not_allowed)
				(footprints allowed)
			)
			(placement
				(enabled no)
				(sheetname "")
			)
			(fill
				(thermal_gap 0.5)
				(thermal_bridge_width 0.5)
				(island_removal_mode 0)
			)
			(polygon
				(pts
					(xy 477.910144 -14.732508) (xy 477.910144 -14.224508) (xy 478.291144 -14.224508) (xy 478.291144 -14.732508)
				)
			)
		)
		(zone
			(layer "F.Cu")
			(hatch none 0.5)
			(connect_pads
				(clearance 0)
			)
			(min_thickness 0.25)
			(keepout
				(tracks allowed)
				(vias not_allowed)
				(pads allowed)
				(copperpour not_allowed)
				(footprints allowed)
			)
			(placement
				(enabled no)
				(sheetname "")
			)
			(fill
				(thermal_gap 0.5)
				(thermal_bridge_width 0.5)
				(island_removal_mode 0)
			)
			(polygon
				(pts
					(xy 478.291144 -14.732508) (xy 478.291144 -14.224508) (xy 477.910144 -14.224508) (xy 477.910144 -14.732508)
				)
			)
		)
	)
)
